(kicad_pcb
	(version 20241229)
	(generator "pcbnew")
	(generator_version "9.0")
	(general
		(thickness 1.63)
		(legacy_teardrops no)
	)
	(paper "A4")
	(title_block
		(title "CM4 Baseboard")
		(date "2026-01-05")
		(rev "1.1.1")
		(company "Antmicro Ltd")
		(comment 1 "www.antmicro.com")
		(comment 9 "footprints 240-245 of 506")
	)
	(layers
		(0 "F.Cu" signal)
		(4 "In1.Cu" power)
		(6 "In2.Cu" power)
		(8 "In3.Cu" signal)
		(10 "In4.Cu" signal)
		(2 "B.Cu" signal)
		(9 "F.Adhes" user "F.Adhesive")
		(11 "B.Adhes" user "B.Adhesive")
		(13 "F.Paste" user)
		(15 "B.Paste" user)
		(5 "F.SilkS" user "F.Silkscreen")
		(7 "B.SilkS" user "B.Silkscreen")
		(1 "F.Mask" user)
		(3 "B.Mask" user)
		(17 "Dwgs.User" user "User.Drawings")
		(19 "Cmts.User" user "User.Comments")
		(21 "Eco1.User" user "User.Eco1")
		(23 "Eco2.User" user "User.Eco2")
		(25 "Edge.Cuts" user)
		(27 "Margin" user)
		(31 "F.CrtYd" user "F.Courtyard")
		(29 "B.CrtYd" user "B.Courtyard")
		(35 "F.Fab" user)
		(33 "B.Fab" user)
	)
	(footprint "antmicro-footprints:C_0402_1005Metric"
		(layer "F.Cu")
		(at 83.567962 139.332236 180)
		(descr "Capacitor SMD 0402")
		(tags "capacitor SMD 0402")
		(property "Reference" "C922"
			(at 1.12 -0.484264 0)
			(layer "F.SilkS")
			(effects
				(font
					(size 0.7 0.7)
					(thickness 0.15)
				)
				(justify right bottom)
			)
		)
		(property "Value" "C_100n_0402"
			(at -1.022927 2.155213 0)
			(layer "F.Fab")
			(effects
				(font
					(size 0.7 0.7)
					(thickness 0.15)
				)
				(justify right bottom)
			)
		)
		(property "Datasheet" "https://www.murata.com/products/productdetail?partno=GRM155R61H104KE14%23"
			(at 0 0 180)
			(layer "F.Fab")
			(hide yes)
			(effects
				(font
					(size 1.27 1.27)
					(thickness 0.15)
				)
			)
		)
		(property "Manufacturer" "Murata"
			(at 0 0 180)
			(unlocked yes)
			(layer "F.Fab")
			(hide yes)
			(effects
				(font
					(size 1 1)
					(thickness 0.15)
				)
			)
		)
		(property "MPN" "GRM155R61H104KE14D"
			(at 0 0 180)
			(unlocked yes)
			(layer "F.Fab")
			(hide yes)
			(effects
				(font
					(size 1 1)
					(thickness 0.15)
				)
			)
		)
		(property "Val" "100n"
			(at 0 0 180)
			(unlocked yes)
			(layer "F.Fab")
			(hide yes)
			(effects
				(font
					(size 1 1)
					(thickness 0.15)
				)
			)
		)
		(property "License" "Apache-2.0"
			(at 0 0 180)
			(unlocked yes)
			(layer "F.Fab")
			(hide yes)
			(effects
				(font
					(size 1 1)
					(thickness 0.15)
				)
			)
		)
		(property "Author" "Antmicro"
			(at 0 0 180)
			(unlocked yes)
			(layer "F.Fab")
			(hide yes)
			(effects
				(font
					(size 1 1)
					(thickness 0.15)
				)
			)
		)
		(property "Voltage" "50V"
			(at 0 0 180)
			(unlocked yes)
			(layer "F.Fab")
			(hide yes)
			(effects
				(font
					(size 1 1)
					(thickness 0.15)
				)
			)
		)
		(property "Dielectric" "X5R"
			(at 0 0 180)
			(unlocked yes)
			(layer "F.Fab")
			(hide yes)
			(effects
				(font
					(size 1 1)
					(thickness 0.15)
				)
			)
		)
		(sheetname "/USB/")
		(sheetfile "usb.kicad_sch")
		(attr smd)
		(fp_rect
			(start -0.925 -0.47)
			(end 0.925 0.47)
			(stroke
				(width 0.05)
				(type default)
			)
			(fill no)
			(layer "F.CrtYd")
		)
		(fp_line
			(start 0.504 0.248)
			(end -0.494 0.248)
			(stroke
				(width 0.15)
				(type solid)
			)
			(layer "F.Fab")
		)
		(fp_line
			(start 0.504 -0.25)
			(end 0.504 0.248)
			(stroke
				(width 0.15)
				(type solid)
			)
			(layer "F.Fab")
		)
		(fp_line
			(start -0.494 0.248)
			(end -0.494 -0.25)
			(stroke
				(width 0.15)
				(type solid)
			)
			(layer "F.Fab")
		)
		(fp_line
			(start -0.494 -0.25)
			(end 0.504 -0.25)
			(stroke
				(width 0.15)
				(type solid)
			)
			(layer "F.Fab")
		)
		(fp_text user "License: Apache-2.0"
			(at -0.939 5.799 180)
			(layer "F.Fab")
			(effects
				(font
					(size 0.7 0.7)
					(thickness 0.15)
				)
				(justify left bottom)
			)
		)
		(fp_text user "${REFERENCE}"
			(at -0.939 4.599 180)
			(layer "F.Fab")
			(effects
				(font
					(size 0.7 0.7)
					(thickness 0.15)
				)
				(justify left bottom)
			)
		)
		(fp_text user "Author: Antmicro"
			(at -0.939 3.399 180)
			(layer "F.Fab")
			(effects
				(font
					(size 0.7 0.7)
					(thickness 0.15)
				)
				(justify left bottom)
			)
		)
		(pad "1" smd roundrect
			(at -0.48 0 180)
			(size 0.59 0.64)
			(layers "F.Cu" "F.Mask" "F.Paste")
			(roundrect_rratio 0.25)
			(net 27 "/USB/USB_3V3")
			(pintype "passive")
		)
		(pad "2" smd roundrect
			(at 0.48 0 180)
			(size 0.59 0.64)
			(layers "F.Cu" "F.Mask" "F.Paste")
			(roundrect_rratio 0.25)
			(net 3 "GND")
			(pintype "passive")
		)
	)
	(footprint "antmicro-footprints:R_0402_1005Metric"
		(layer "F.Cu")
		(at 102.067962 144.6165 180)
		(descr "Resistor SMD 0402")
		(tags "resistor SMD 0402")
		(property "Reference" "R929"
			(at -3.6 -0.45 0)
			(layer "F.SilkS")
			(effects
				(font
					(size 0.7 0.7)
					(thickness 0.15)
				)
				(justify right bottom)
			)
		)
		(property "Value" "R_10k_0402"
			(at -1.011843 1.772047 0)
			(layer "F.Fab")
			(effects
				(font
					(size 0.7 0.7)
					(thickness 0.15)
				)
				(justify right bottom)
			)
		)
		(property "Datasheet" "https://www.bourns.com/docs/product-datasheets/cr.pdf"
			(at 0 0 180)
			(layer "F.Fab")
			(hide yes)
			(effects
				(font
					(size 1.27 1.27)
					(thickness 0.15)
				)
			)
		)
		(property "Manufacturer" "Bourns"
			(at 0 0 180)
			(unlocked yes)
			(layer "F.Fab")
			(hide yes)
			(effects
				(font
					(size 1 1)
					(thickness 0.15)
				)
			)
		)
		(property "MPN" "CR0402-FX-1002GLF"
			(at 0 0 180)
			(unlocked yes)
			(layer "F.Fab")
			(hide yes)
			(effects
				(font
					(size 1 1)
					(thickness 0.15)
				)
			)
		)
		(property "Val" "10k"
			(at 0 0 180)
			(unlocked yes)
			(layer "F.Fab")
			(hide yes)
			(effects
				(font
					(size 1 1)
					(thickness 0.15)
				)
			)
		)
		(property "License" "Apache-2.0"
			(at 0 0 180)
			(unlocked yes)
			(layer "F.Fab")
			(hide yes)
			(effects
				(font
					(size 1 1)
					(thickness 0.15)
				)
			)
		)
		(property "Author" "Antmicro"
			(at 0 0 180)
			(unlocked yes)
			(layer "F.Fab")
			(hide yes)
			(effects
				(font
					(size 1 1)
					(thickness 0.15)
				)
			)
		)
		(property "Tolerance" "1%"
			(at 0 0 180)
			(unlocked yes)
			(layer "F.Fab")
			(hide yes)
			(effects
				(font
					(size 1 1)
					(thickness 0.15)
				)
			)
		)
		(sheetname "/USB/")
		(sheetfile "usb.kicad_sch")
		(attr smd)
		(fp_rect
			(start -0.925 -0.47)
			(end 0.925 0.47)
			(stroke
				(width 0.05)
				(type default)
			)
			(fill no)
			(layer "F.CrtYd")
		)
		(fp_rect
			(start -0.5 -0.25)
			(end 0.5 0.25)
			(stroke
				(width 0.15)
				(type solid)
			)
			(fill no)
			(layer "F.Fab")
		)
		(fp_text user "License: Apache-2.0"
			(at -0.95 5.169 180)
			(layer "F.Fab")
			(effects
				(font
					(size 0.7 0.7)
					(thickness 0.15)
				)
				(justify left bottom)
			)
		)
		(fp_text user "Author: Antmicro"
			(at -0.95 4.169 180)
			(layer "F.Fab")
			(effects
				(font
					(size 0.7 0.7)
					(thickness 0.15)
				)
				(justify left bottom)
			)
		)
		(fp_text user "${REFERENCE}"
			(at -0.95 3.168 180)
			(layer "F.Fab")
			(effects
				(font
					(size 0.7 0.7)
					(thickness 0.15)
				)
				(justify left bottom)
			)
		)
		(pad "1" smd roundrect
			(at -0.48 0 180)
			(size 0.59 0.64)
			(layers "F.Cu" "F.Mask" "F.Paste")
			(roundrect_rratio 0.25)
			(net 490 "Net-(Q905-G)")
			(pintype "passive")
		)
		(pad "2" smd roundrect
			(at 0.48 0 180)
			(size 0.59 0.64)
			(layers "F.Cu" "F.Mask" "F.Paste")
			(roundrect_rratio 0.25)
			(net 3 "GND")
			(pintype "passive")
		)
	)
	(footprint "antmicro-footprints:TP_SMD_0.75mm"
		(layer "F.Cu")
		(at 70.567962 178.2915 -90)
		(property "Reference" "TP803"
			(at 1.3085 2.867962 0)
			(layer "F.SilkS")
			(effects
				(font
					(size 0.7 0.65)
					(thickness 0.15)
				)
				(justify left bottom)
			)
		)
		(property "Value" "TP_0.75mm_SMD"
			(at 0 1.2 270)
			(layer "F.Fab")
			(effects
				(font
					(size 0.7 0.7)
					(thickness 0.15)
				)
				(justify left bottom)
			)
		)
		(property "Author" "Antmicro"
			(at 0 0 270)
			(unlocked yes)
			(layer "F.Fab")
			(hide yes)
			(effects
				(font
					(size 1 1)
					(thickness 0.15)
				)
			)
		)
		(property "License" "Apache-2.0"
			(at 0 0 270)
			(unlocked yes)
			(layer "F.Fab")
			(hide yes)
			(effects
				(font
					(size 1 1)
					(thickness 0.15)
				)
			)
		)
		(property "MPN" ""
			(at 0 0 270)
			(unlocked yes)
			(layer "F.Fab")
			(hide yes)
			(effects
				(font
					(size 1 1)
					(thickness 0.15)
				)
			)
		)
		(property "Manufacturer" ""
			(at 0 0 270)
			(unlocked yes)
			(layer "F.Fab")
			(hide yes)
			(effects
				(font
					(size 1 1)
					(thickness 0.15)
				)
			)
		)
		(sheetname "/Peripherals/")
		(sheetfile "peripherals.kicad_sch")
		(attr exclude_from_pos_files exclude_from_bom)
		(fp_circle
			(center 0 0)
			(end 0.475 0)
			(stroke
				(width 0.05)
				(type default)
			)
			(fill no)
			(layer "F.CrtYd")
		)
		(fp_text user "${REFERENCE}"
			(at -0.4 2.7 270)
			(layer "F.Fab")
			(effects
				(font
					(size 0.7 0.7)
					(thickness 0.15)
				)
				(justify left bottom)
			)
		)
		(fp_text user "License: Apache-2.0"
			(at -0.4 5.101 270)
			(layer "F.Fab")
			(effects
				(font
					(size 0.7 0.7)
					(thickness 0.15)
				)
				(justify left bottom)
			)
		)
		(fp_text user "Author: Antmicro"
			(at -0.4 3.901 270)
			(layer "F.Fab")
			(effects
				(font
					(size 0.7 0.7)
					(thickness 0.15)
				)
				(justify left bottom)
			)
		)
		(pad "1" smd circle
			(at 0 0 270)
			(size 0.75 0.75)
			(layers "F.Cu" "F.Mask")
			(net 383 "Net-(U801-V_{DD(HF)})")
			(pinfunction "1")
			(pintype "passive")
		)
	)
	(footprint "antmicro-footprints:R_0402_1005Metric"
		(layer "F.Cu")
		(at 54.847962 128.8965)
		(descr "Resistor SMD 0402")
		(tags "resistor SMD 0402")
		(property "Reference" "R406"
			(at -1.49 -5.38 0)
			(layer "F.SilkS")
			(effects
				(font
					(size 0.7 0.7)
					(thickness 0.15)
				)
				(justify left bottom)
			)
		)
		(property "Value" "R_24k9_0402"
			(at -1.011843 1.772047 0)
			(layer "F.Fab")
			(effects
				(font
					(size 0.7 0.7)
					(thickness 0.15)
				)
				(justify left bottom)
			)
		)
		(property "Datasheet" "https://www.bourns.com/docs/product-datasheets/cr.pdf"
			(at 0 0 0)
			(layer "F.Fab")
			(hide yes)
			(effects
				(font
					(size 1.27 1.27)
					(thickness 0.15)
				)
			)
		)
		(property "Manufacturer" "Bourns"
			(at 0 0 0)
			(unlocked yes)
			(layer "F.Fab")
			(hide yes)
			(effects
				(font
					(size 1 1)
					(thickness 0.15)
				)
			)
		)
		(property "MPN" "CR0402-FX-2492GLF"
			(at 0 0 0)
			(unlocked yes)
			(layer "F.Fab")
			(hide yes)
			(effects
				(font
					(size 1 1)
					(thickness 0.15)
				)
			)
		)
		(property "Val" "24k9"
			(at 0 0 0)
			(unlocked yes)
			(layer "F.Fab")
			(hide yes)
			(effects
				(font
					(size 1 1)
					(thickness 0.15)
				)
			)
		)
		(property "License" "Apache-2.0"
			(at 0 0 0)
			(unlocked yes)
			(layer "F.Fab")
			(hide yes)
			(effects
				(font
					(size 1 1)
					(thickness 0.15)
				)
			)
		)
		(property "Author" "Antmicro"
			(at 0 0 0)
			(unlocked yes)
			(layer "F.Fab")
			(hide yes)
			(effects
				(font
					(size 1 1)
					(thickness 0.15)
				)
			)
		)
		(property "Tolerance" "1%"
			(at 0 0 0)
			(unlocked yes)
			(layer "F.Fab")
			(hide yes)
			(effects
				(font
					(size 1 1)
					(thickness 0.15)
				)
			)
		)
		(sheetname "/Ethernet/")
		(sheetfile "ethernet.kicad_sch")
		(attr smd)
		(fp_rect
			(start -0.925 -0.47)
			(end 0.925 0.47)
			(stroke
				(width 0.05)
				(type default)
			)
			(fill no)
			(layer "F.CrtYd")
		)
		(fp_rect
			(start -0.5 -0.25)
			(end 0.5 0.25)
			(stroke
				(width 0.15)
				(type solid)
			)
			(fill no)
			(layer "F.Fab")
		)
		(fp_text user "License: Apache-2.0"
			(at -0.95 5.169 0)
			(layer "F.Fab")
			(effects
				(font
					(size 0.7 0.7)
					(thickness 0.15)
				)
				(justify left bottom)
			)
		)
		(fp_text user "${REFERENCE}"
			(at -0.95 3.168 0)
			(layer "F.Fab")
			(effects
				(font
					(size 0.7 0.7)
					(thickness 0.15)
				)
				(justify left bottom)
			)
		)
		(fp_text user "Author: Antmicro"
			(at -0.95 4.169 0)
			(layer "F.Fab")
			(effects
				(font
					(size 0.7 0.7)
					(thickness 0.15)
				)
				(justify left bottom)
			)
		)
		(pad "1" smd roundrect
			(at -0.48 0)
			(size 0.59 0.64)
			(layers "F.Cu" "F.Mask" "F.Paste")
			(roundrect_rratio 0.25)
			(net 361 "/Ethernet/DEN")
			(pintype "passive")
		)
		(pad "2" smd roundrect
			(at 0.48 0)
			(size 0.59 0.64)
			(layers "F.Cu" "F.Mask" "F.Paste")
			(roundrect_rratio 0.25)
			(net 33 "/Ethernet/VDD")
			(pintype "passive")
		)
	)
	(footprint "antmicro-footprints:C_0402_1005Metric"
		(layer "F.Cu")
		(at 95.592962 141.1165)
		(descr "Capacitor SMD 0402")
		(tags "capacitor SMD 0402")
		(property "Reference" "C915"
			(at 0.625 0.05 0)
			(layer "F.SilkS")
			(effects
				(font
					(size 0.7 0.7)
					(thickness 0.15)
				)
				(justify left bottom)
			)
		)
		(property "Value" "C_100n_0402"
			(at -1.022927 2.155213 0)
			(layer "F.Fab")
			(effects
				(font
					(size 0.7 0.7)
					(thickness 0.15)
				)
				(justify left bottom)
			)
		)
		(property "Datasheet" "https://www.murata.com/products/productdetail?partno=GRM155R61H104KE14%23"
			(at 0 0 0)
			(layer "F.Fab")
			(hide yes)
			(effects
				(font
					(size 1.27 1.27)
					(thickness 0.15)
				)
			)
		)
		(property "Manufacturer" "Murata"
			(at 0 0 0)
			(unlocked yes)
			(layer "F.Fab")
			(hide yes)
			(effects
				(font
					(size 1 1)
					(thickness 0.15)
				)
			)
		)
		(property "MPN" "GRM155R61H104KE14D"
			(at 0 0 0)
			(unlocked yes)
			(layer "F.Fab")
			(hide yes)
			(effects
				(font
					(size 1 1)
					(thickness 0.15)
				)
			)
		)
		(property "Val" "100n"
			(at 0 0 0)
			(unlocked yes)
			(layer "F.Fab")
			(hide yes)
			(effects
				(font
					(size 1 1)
					(thickness 0.15)
				)
			)
		)
		(property "License" "Apache-2.0"
			(at 0 0 0)
			(unlocked yes)
			(layer "F.Fab")
			(hide yes)
			(effects
				(font
					(size 1 1)
					(thickness 0.15)
				)
			)
		)
		(property "Author" "Antmicro"
			(at 0 0 0)
			(unlocked yes)
			(layer "F.Fab")
			(hide yes)
			(effects
				(font
					(size 1 1)
					(thickness 0.15)
				)
			)
		)
		(property "Voltage" "50V"
			(at 0 0 0)
			(unlocked yes)
			(layer "F.Fab")
			(hide yes)
			(effects
				(font
					(size 1 1)
					(thickness 0.15)
				)
			)
		)
		(property "Dielectric" "X5R"
			(at 0 0 0)
			(unlocked yes)
			(layer "F.Fab")
			(hide yes)
			(effects
				(font
					(size 1 1)
					(thickness 0.15)
				)
			)
		)
		(sheetname "/USB/")
		(sheetfile "usb.kicad_sch")
		(attr smd)
		(fp_rect
			(start -0.925 -0.47)
			(end 0.925 0.47)
			(stroke
				(width 0.05)
				(type default)
			)
			(fill no)
			(layer "F.CrtYd")
		)
		(fp_line
			(start -0.494 -0.25)
			(end 0.504 -0.25)
			(stroke
				(width 0.15)
				(type solid)
			)
			(layer "F.Fab")
		)
		(fp_line
			(start -0.494 0.248)
			(end -0.494 -0.25)
			(stroke
				(width 0.15)
				(type solid)
			)
			(layer "F.Fab")
		)
		(fp_line
			(start 0.504 -0.25)
			(end 0.504 0.248)
			(stroke
				(width 0.15)
				(type solid)
			)
			(layer "F.Fab")
		)
		(fp_line
			(start 0.504 0.248)
			(end -0.494 0.248)
			(stroke
				(width 0.15)
				(type solid)
			)
			(layer "F.Fab")
		)
		(fp_text user "${REFERENCE}"
			(at -0.939 4.599 0)
			(layer "F.Fab")
			(effects
				(font
					(size 0.7 0.7)
					(thickness 0.15)
				)
				(justify left bottom)
			)
		)
		(fp_text user "Author: Antmicro"
			(at -0.939 3.399 0)
			(layer "F.Fab")
			(effects
				(font
					(size 0.7 0.7)
					(thickness 0.15)
				)
				(justify left bottom)
			)
		)
		(fp_text user "License: Apache-2.0"
			(at -0.939 5.799 0)
			(layer "F.Fab")
			(effects
				(font
					(size 0.7 0.7)
					(thickness 0.15)
				)
				(justify left bottom)
			)
		)
		(pad "1" smd roundrect
			(at -0.48 0)
			(size 0.59 0.64)
			(layers "F.Cu" "F.Mask" "F.Paste")
			(roundrect_rratio 0.25)
			(net 27 "/USB/USB_3V3")
			(pintype "passive")
		)
		(pad "2" smd roundrect
			(at 0.48 0)
			(size 0.59 0.64)
			(layers "F.Cu" "F.Mask" "F.Paste")
			(roundrect_rratio 0.25)
			(net 3 "GND")
			(pintype "passive")
		)
	)
	(footprint "antmicro-footprints:R_0402_1005Metric"
		(layer "F.Cu")
		(at 53.017962 135.3415 90)
		(descr "Resistor SMD 0402")
		(tags "resistor SMD 0402")
		(property "Reference" "R416"
			(at -1.8693 -4.072162 180)
			(layer "F.SilkS")
			(effects
				(font
					(size 0.7 0.7)
					(thickness 0.15)
				)
				(justify left bottom)
			)
		)
		(property "Value" "R_100k_0402"
			(at -1.011843 1.772047 90)
			(layer "F.Fab")
			(effects
				(font
					(size 0.7 0.7)
					(thickness 0.15)
				)
				(justify left bottom)
			)
		)
		(property "Datasheet" "https://www.bourns.com/docs/product-datasheets/cr.pdf"
			(at 0 0 90)
			(layer "F.Fab")
			(hide yes)
			(effects
				(font
					(size 1.27 1.27)
					(thickness 0.15)
				)
			)
		)
		(property "Manufacturer" "Bourns"
			(at 0 0 90)
			(unlocked yes)
			(layer "F.Fab")
			(hide yes)
			(effects
				(font
					(size 1 1)
					(thickness 0.15)
				)
			)
		)
		(property "MPN" "CR0402-FX-1003GLF"
			(at 0 0 90)
			(unlocked yes)
			(layer "F.Fab")
			(hide yes)
			(effects
				(font
					(size 1 1)
					(thickness 0.15)
				)
			)
		)
		(property "Val" "100k"
			(at 0 0 90)
			(unlocked yes)
			(layer "F.Fab")
			(hide yes)
			(effects
				(font
					(size 1 1)
					(thickness 0.15)
				)
			)
		)
		(property "License" "Apache-2.0"
			(at 0 0 90)
			(unlocked yes)
			(layer "F.Fab")
			(hide yes)
			(effects
				(font
					(size 1 1)
					(thickness 0.15)
				)
			)
		)
		(property "Author" "Antmicro"
			(at 0 0 90)
			(unlocked yes)
			(layer "F.Fab")
			(hide yes)
			(effects
				(font
					(size 1 1)
					(thickness 0.15)
				)
			)
		)
		(property "Tolerance" "1%"
			(at 0 0 90)
			(unlocked yes)
			(layer "F.Fab")
			(hide yes)
			(effects
				(font
					(size 1 1)
					(thickness 0.15)
				)
			)
		)
		(sheetname "/Ethernet/")
		(sheetfile "ethernet.kicad_sch")
		(attr smd)
		(fp_rect
			(start -0.925 -0.47)
			(end 0.925 0.47)
			(stroke
				(width 0.05)
				(type default)
			)
			(fill no)
			(layer "F.CrtYd")
		)
		(fp_rect
			(start -0.5 -0.25)
			(end 0.5 0.25)
			(stroke
				(width 0.15)
				(type solid)
			)
			(fill no)
			(layer "F.Fab")
		)
		(fp_text user "License: Apache-2.0"
			(at -0.95 5.169 90)
			(layer "F.Fab")
			(effects
				(font
					(size 0.7 0.7)
					(thickness 0.15)
				)
				(justify left bottom)
			)
		)
		(fp_text user "Author: Antmicro"
			(at -0.95 4.169 90)
			(layer "F.Fab")
			(effects
				(font
					(size 0.7 0.7)
					(thickness 0.15)
				)
				(justify left bottom)
			)
		)
		(fp_text user "${REFERENCE}"
			(at -0.95 3.168 90)
			(layer "F.Fab")
			(effects
				(font
					(size 0.7 0.7)
					(thickness 0.15)
				)
				(justify left bottom)
			)
		)
		(pad "1" smd roundrect
			(at -0.48 0 90)
			(size 0.59 0.64)
			(layers "F.Cu" "F.Mask" "F.Paste")
			(roundrect_rratio 0.25)
			(net 1 "GNDD")
			(pintype "passive")
		)
		(pad "2" smd roundrect
			(at 0.48 0 90)
			(size 0.59 0.64)
			(layers "F.Cu" "F.Mask" "F.Paste")
			(roundrect_rratio 0.25)
			(net 339 "/Ethernet/POE_ACTIVE")
			(pintype "passive")
		)
	)
)
